FILE_TYPE=LIBRARY_PARTS;
primitive 'Q_RES_4P_12';
  pin
    '1':
      PIN_NUMBER='(1)';
      PIN_TYPE='ANALOG';
      NO_LOAD_CHECK='Both';
      NO_IO_CHECK='Both';
      NO_ASSERT_CHECK='TRUE';
      NO_DIR_CHECK='TRUE';
      ALLOW_CONNECT='TRUE';
    '2':
      PIN_NUMBER='(2)';
      PIN_TYPE='ANALOG';
      NO_LOAD_CHECK='Both';
      NO_IO_CHECK='Both';
      NO_ASSERT_CHECK='TRUE';
      NO_DIR_CHECK='TRUE';
      ALLOW_CONNECT='TRUE';
    '3':
      PIN_NUMBER='(3)';
      PIN_TYPE='ANALOG';
      NO_LOAD_CHECK='Both';
      NO_IO_CHECK='Both';
      NO_ASSERT_CHECK='TRUE';
      NO_DIR_CHECK='TRUE';
      ALLOW_CONNECT='TRUE';
    '4':
      PIN_NUMBER='(4)';
      PIN_TYPE='ANALOG';
      NO_LOAD_CHECK='Both';
      NO_IO_CHECK='Both';
      NO_ASSERT_CHECK='TRUE';
      NO_DIR_CHECK='TRUE';
      ALLOW_CONNECT='TRUE';
  end_pin;
  body
    PART_NAME='Q_RES_4P_12';
    BODY_NAME='Q_RES_4P_12';
    PHYS_DES_PREFIX='R';
    CLASS='DISCRETE';
  end_body;
end_primitive;

END.
